(kicad_pcb
	(version 20260206)
	(generator "pcbnew")
	(generator_version "10.0")
	(general
		(thickness 1.6)
		(legacy_teardrops no)
	)
	(paper "A4")
	(title_block
		(title "v1-tray-backplane — T6M_tray_BP_c_1023_1120.brd")
		(comment 1 "Open CloudServer (Microsoft) / footprint 90 of 170 (J18), pads 1-20 of 20")
	)
	(layers
		(0 "F.Cu" signal "TOP")
		(4 "In1.Cu" signal "GND")
		(6 "In2.Cu" signal "IN1")
		(8 "In3.Cu" signal "VCC")
		(10 "In4.Cu" signal "VCC1")
		(12 "In5.Cu" signal "IN2")
		(14 "In6.Cu" signal "GND1")
		(2 "B.Cu" signal "BOTTOM")
		(9 "F.Adhes" user "F.Adhesive")
		(11 "B.Adhes" user "B.Adhesive")
		(13 "F.Paste" user "Package Geometry/Pastemask Top")
		(15 "B.Paste" user "Package Geometry/Pastemask Bottom")
		(5 "F.SilkS" user "Ref Des/Silkscreen Top")
		(7 "B.SilkS" user "Ref Des/Silkscreen Bottom")
		(1 "F.Mask" user "Board Geometry/Soldermask Top")
		(3 "B.Mask" user "Board Geometry/Soldermask Bottom")
		(17 "Dwgs.User" user "User.Drawings")
		(19 "Cmts.User" user "User.Comments")
		(21 "Eco1.User" user "User.Eco1")
		(23 "Eco2.User" user "User.Eco2")
		(25 "Edge.Cuts" user "Board Geometry/Outline")
		(27 "Margin" user)
		(31 "F.CrtYd" user "Package Geometry/Place Bound Top")
		(29 "B.CrtYd" user "Package Geometry/Place Bound Bottom")
		(35 "F.Fab" user "Ref Des/Assembly Top")
		(33 "B.Fab" user "Ref Des/Assembly Bottom")
	)
	(footprint ""
		(layer "F.Cu")
		(at 332.695042 -49.795176)
		(property "Reference" "J18"
			(at -19.345148 3.078734 90)
			(unlocked yes)
			(layer "F.SilkS")
			(effects
				(font
					(size 0.7874 0.5842)
					(thickness 0.1524)
				)
				(justify left)
			)
		)
		(property "Value" ""
			(at 0 0 0)
			(layer "F.Fab")
			(effects
				(font
					(size 1.27 1.27)
				)
			)
		)
		(duplicate_pad_numbers_are_jumpers no)
		(pad "1" thru_hole circle
			(at 0 4.500118)
			(size 1.5494 1.5494)
			(drill 1.0414)
			(layers "*.Cu" "*.Mask")
			(remove_unused_layers no)
			(net "GND")
			(clearance 0)
		)
		(pad "2" thru_hole circle
			(at -8.58012 4.500118)
			(size 1.5494 1.5494)
			(drill 1.0414)
			(layers "*.Cu" "*.Mask")
			(remove_unused_layers no)
			(net "GND")
			(clearance 0)
		)
		(pad "3" thru_hole circle
			(at 0 14.500098)
			(size 1.5494 1.5494)
			(drill 1.0414)
			(layers "*.Cu" "*.Mask")
			(remove_unused_layers no)
			(net "GND")
			(clearance 0)
		)
		(pad "4" thru_hole circle
			(at -14.249908 9.500108)
			(size 1.5494 1.5494)
			(drill 1.0414)
			(layers "*.Cu" "*.Mask")
			(remove_unused_layers no)
			(net "GND")
			(clearance 0)
		)
		(pad "5" thru_hole circle
			(at -14.249908 19.500088)
			(size 1.5494 1.5494)
			(drill 1.0414)
			(layers "*.Cu" "*.Mask")
			(remove_unused_layers no)
			(net "GND")
			(clearance 0)
		)
		(pad "6" thru_hole circle
			(at 0 24.500078)
			(size 1.5494 1.5494)
			(drill 1.0414)
			(layers "*.Cu" "*.Mask")
			(remove_unused_layers no)
			(net "GND")
			(clearance 0)
		)
		(pad "7" thru_hole circle
			(at -5.679948 24.500078)
			(size 1.5494 1.5494)
			(drill 1.0414)
			(layers "*.Cu" "*.Mask")
			(remove_unused_layers no)
			(net "GND")
			(clearance 0)
		)
		(pad "8" thru_hole circle
			(at -11.079988 24.500078)
			(size 1.5494 1.5494)
			(drill 1.0414)
			(layers "*.Cu" "*.Mask")
			(remove_unused_layers no)
			(net "GND")
			(clearance 0)
		)
		(pad "9" thru_hole circle
			(at -14.249908 29.500068)
			(size 1.5494 1.5494)
			(drill 1.0414)
			(layers "*.Cu" "*.Mask")
			(remove_unused_layers no)
			(net "GND")
			(clearance 0)
		)
		(pad "10" thru_hole circle
			(at -14.249908 39.500048)
			(size 1.5494 1.5494)
			(drill 1.0414)
			(layers "*.Cu" "*.Mask")
			(remove_unused_layers no)
			(net "GND")
			(clearance 0)
		)
		(pad "11" thru_hole circle
			(at 0 27.29992)
			(size 1.3462 1.3462)
			(drill 0.9398)
			(layers "*.Cu" "*.Mask")
			(remove_unused_layers no)
			(net "GND")
			(clearance 0.0508)
			(thermal_gap 0.0508)
		)
		(pad "12" thru_hole circle
			(at 0 31.999936)
			(size 1.3462 1.3462)
			(drill 0.9398)
			(layers "*.Cu" "*.Mask")
			(remove_unused_layers no)
			(net "GND")
			(clearance 0.0508)
			(thermal_gap 0.0508)
		)
		(pad "13" thru_hole circle
			(at 0 36.999926)
			(size 1.3462 1.3462)
			(drill 0.9398)
			(layers "*.Cu" "*.Mask")
			(remove_unused_layers no)
			(net "GND")
			(clearance 0.0508)
			(thermal_gap 0.0508)
		)
		(pad "14" thru_hole circle
			(at -2.329942 41.60012)
			(size 1.3462 1.3462)
			(drill 0.9398)
			(layers "*.Cu" "*.Mask")
			(remove_unused_layers no)
			(net "GND")
			(clearance 0.0508)
			(thermal_gap 0.0508)
		)
		(pad "15" thru_hole circle
			(at -7.130034 41.60012)
			(size 1.3462 1.3462)
			(drill 0.9398)
			(layers "*.Cu" "*.Mask")
			(remove_unused_layers no)
			(net "GND")
			(clearance 0.0508)
			(thermal_gap 0.0508)
		)
		(pad "16" thru_hole circle
			(at -11.929872 41.60012)
			(size 1.3462 1.3462)
			(drill 0.9398)
			(layers "*.Cu" "*.Mask")
			(remove_unused_layers no)
			(net "GND")
			(clearance 0.0508)
			(thermal_gap 0.0508)
		)
		(pad "17" thru_hole circle
			(at -14.249908 27.29992)
			(size 1.3462 1.3462)
			(drill 0.9398)
			(layers "*.Cu" "*.Mask")
			(remove_unused_layers no)
			(net "GND")
			(clearance 0.0508)
			(thermal_gap 0.0508)
		)
		(pad "18" thru_hole circle
			(at -14.249908 31.999936)
			(size 1.3462 1.3462)
			(drill 0.9398)
			(layers "*.Cu" "*.Mask")
			(remove_unused_layers no)
			(net "GND")
			(clearance 0.0508)
			(thermal_gap 0.0508)
		)
		(pad "19" thru_hole circle
			(at -14.249908 36.999926)
			(size 1.3462 1.3462)
			(drill 0.9398)
			(layers "*.Cu" "*.Mask")
			(remove_unused_layers no)
			(net "GND")
			(clearance 0.0508)
			(thermal_gap 0.0508)
		)
		(pad "20" thru_hole circle
			(at 0 34.500058)
			(size 1.2446 1.2446)
			(drill 0.8382)
			(layers "*.Cu" "*.Mask")
			(remove_unused_layers no)
			(net "GND")
			(clearance 0.0508)
			(thermal_gap 0.0508)
		)
	)
)
